(kicad_pcb
	(version 20260206)
	(generator "pcbnew")
	(generator_version "10.0")
	(general
		(thickness 1.6)
		(legacy_teardrops no)
	)
	(paper "A4")
	(title_block
		(title "timecard-production-celestica-r4006 — R4006-B0001-02_R01.brd")
		(comment 1 "Time Appliance Project (Time Card) / footprints 827-831 of 1113")
	)
	(layers
		(0 "F.Cu" signal "TOP")
		(4 "In1.Cu" signal "L02_GND1")
		(6 "In2.Cu" signal "L03_SIG1")
		(8 "In3.Cu" signal "L04_GND2")
		(10 "In4.Cu" signal "L05_VCC1")
		(12 "In5.Cu" signal "L06_VCC2")
		(14 "In6.Cu" signal "L07_GND3")
		(16 "In7.Cu" signal "L08_SIG2")
		(18 "In8.Cu" signal "L09_GND4")
		(2 "B.Cu" signal "BOTTOM")
		(9 "F.Adhes" user "F.Adhesive")
		(11 "B.Adhes" user "B.Adhesive")
		(13 "F.Paste" user "Package Geometry/Pastemask Top")
		(15 "B.Paste" user "Package Geometry/Pastemask Bottom")
		(5 "F.SilkS" user "Ref Des/Silkscreen Top")
		(7 "B.SilkS" user "Ref Des/Silkscreen Bottom")
		(1 "F.Mask" user "Board Geometry/Soldermask Top")
		(3 "B.Mask" user "Board Geometry/Soldermask Bottom")
		(17 "Dwgs.User" user "User.Drawings")
		(19 "Cmts.User" user "User.Comments")
		(21 "Eco1.User" user "User.Eco1")
		(23 "Eco2.User" user "User.Eco2")
		(25 "Edge.Cuts" user "Board Geometry/Outline")
		(27 "Margin" user)
		(31 "F.CrtYd" user "Package Geometry/Place Bound Top")
		(29 "B.CrtYd" user "Package Geometry/Place Bound Bottom")
		(35 "F.Fab" user "Ref Des/Assembly Top")
		(33 "B.Fab" user "Ref Des/Assembly Bottom")
	)
	(footprint ""
		(layer "B.Cu")
		(at 156.337 -45.466 90)
		(property "Reference" "R430"
			(at -10.70737 -0.254 0)
			(unlocked yes)
			(layer "B.SilkS")
			(effects
				(font
					(size 0.7874 0.5842)
					(thickness 0.1524)
				)
				(justify mirror)
			)
		)
		(property "Value" "VAL*"
			(at -0.02032 2.13233 90)
			(unlocked yes)
			(layer "B.Fab")
			(hide yes)
			(effects
				(font
					(size 0.7874 0.5842)
					(thickness 0.1524)
				)
				(justify mirror)
			)
		)
		(property "Tolerance" "TOL*"
			(at -0.044704 3.05435 90)
			(unlocked yes)
			(layer "Cmts.User")
			(hide yes)
			(effects
				(font
					(size 0.7874 0.5842)
					(thickness 0.1524)
				)
				(justify mirror)
			)
		)
		(property "User Part Number" "PARTNUM*"
			(at -0.02032 4.024884 90)
			(unlocked yes)
			(layer "Cmts.User")
			(hide yes)
			(effects
				(font
					(size 0.7874 0.5842)
					(thickness 0.1524)
				)
				(justify mirror)
			)
		)
		(property "Device Type" "RESISTOR-G155-133R0-01,33OHM,1%"
			(at -0.008382 1.210564 90)
			(unlocked yes)
			(layer "B.Fab")
			(hide yes)
			(effects
				(font
					(size 0.7874 0.5842)
					(thickness 0.1524)
				)
				(justify mirror)
			)
		)
		(duplicate_pad_numbers_are_jumpers no)
		(fp_line
			(start 1.143 -0.5588)
			(end 1.143 0.5588)
			(stroke
				(width 0.1)
				(type default)
			)
			(layer "B.SilkS")
		)
		(fp_line
			(start -1.143 -0.5588)
			(end 1.143 -0.5588)
			(stroke
				(width 0.1)
				(type default)
			)
			(layer "B.SilkS")
		)
		(fp_line
			(start 1.143 0.5588)
			(end -1.143 0.5588)
			(stroke
				(width 0.1)
				(type default)
			)
			(layer "B.SilkS")
		)
		(fp_line
			(start -1.143 0.5588)
			(end -1.143 -0.5588)
			(stroke
				(width 0.1)
				(type default)
			)
			(layer "B.SilkS")
		)
		(fp_poly
			(pts
				(xy 1.143 0.5588) (xy -1.143 0.5588) (xy -1.143 -0.5588) (xy 1.143 -0.5588)
			)
			(stroke
				(width 0)
				(type default)
			)
			(fill no)
			(layer "B.CrtYd")
		)
		(fp_line
			(start 0.508 -0.3048)
			(end 0.508 0.3048)
			(stroke
				(width 0.1)
				(type default)
			)
			(layer "B.Fab")
		)
		(fp_line
			(start -0.508 -0.3048)
			(end 0.508 -0.3048)
			(stroke
				(width 0.1)
				(type default)
			)
			(layer "B.Fab")
		)
		(fp_line
			(start 0.508 0.3048)
			(end -0.508 0.3048)
			(stroke
				(width 0.1)
				(type default)
			)
			(layer "B.Fab")
		)
		(fp_line
			(start -0.508 0.3048)
			(end -0.508 -0.3048)
			(stroke
				(width 0.1)
				(type default)
			)
			(layer "B.Fab")
		)
		(pad "1" smd rect
			(at 0.5334 0 270)
			(size 0.7112 0.6096)
			(layers "B.Cu" "B.Mask" "B.Paste")
			(net "FPGA_IO_4")
		)
		(pad "2" smd rect
			(at -0.5334 0 270)
			(size 0.7112 0.6096)
			(layers "B.Cu" "B.Mask" "B.Paste")
			(net "UNNAMED_16_CONNHDR2X6FSSMT_I161")
		)
		(zone
			(layer "B.Cu")
			(hatch none 0.5)
			(connect_pads
				(clearance 0)
			)
			(min_thickness 0.25)
			(keepout
				(tracks not_allowed)
				(vias allowed)
				(pads allowed)
				(copperpour not_allowed)
				(footprints allowed)
			)
			(placement
				(enabled no)
				(sheetname "")
			)
			(fill
				(thermal_gap 0.5)
				(thermal_bridge_width 0.5)
				(island_removal_mode 0)
			)
			(polygon
				(pts
					(xy 156.6418 -45.5422) (xy 156.0322 -45.5422) (xy 156.0322 -45.3898) (xy 156.6418 -45.3898)
				)
			)
		)
		(zone
			(layer "B.Cu")
			(hatch none 0.5)
			(connect_pads
				(clearance 0)
			)
			(min_thickness 0.25)
			(keepout
				(tracks allowed)
				(vias not_allowed)
				(pads allowed)
				(copperpour not_allowed)
				(footprints allowed)
			)
			(placement
				(enabled no)
				(sheetname "")
			)
			(fill
				(thermal_gap 0.5)
				(thermal_bridge_width 0.5)
				(island_removal_mode 0)
			)
			(polygon
				(pts
					(xy 156.6418 -45.5422) (xy 156.0322 -45.5422) (xy 156.0322 -45.3898) (xy 156.6418 -45.3898)
				)
			)
		)
	)
	(footprint ""
		(layer "B.Cu")
		(at 110.3376 -44.2214)
		(property "Reference" "C212"
			(at -43.4086 1.45415 0)
			(unlocked yes)
			(layer "B.SilkS")
			(effects
				(font
					(size 0.635 0.4064)
					(thickness 0.1524)
				)
				(justify mirror)
			)
		)
		(property "Value" "VAL*"
			(at -0.0762 2.067306 0)
			(unlocked yes)
			(layer "B.Fab")
			(hide yes)
			(effects
				(font
					(size 0.7874 0.5842)
					(thickness 0.1524)
				)
				(justify mirror)
			)
		)
		(property "Device Type" "CAPACITOR-G105-0B104-CK,0.1UF,A"
			(at -0.0508 1.127506 0)
			(unlocked yes)
			(layer "B.Fab")
			(hide yes)
			(effects
				(font
					(size 0.7874 0.5842)
					(thickness 0.1524)
				)
				(justify mirror)
			)
		)
		(property "User Part Number" "PARTNUM*"
			(at -0.1016 4.023106 0)
			(unlocked yes)
			(layer "Cmts.User")
			(hide yes)
			(effects
				(font
					(size 0.7874 0.5842)
					(thickness 0.1524)
				)
				(justify mirror)
			)
		)
		(property "Tolerance" "TOL*"
			(at -0.0762 3.032506 0)
			(unlocked yes)
			(layer "Cmts.User")
			(hide yes)
			(effects
				(font
					(size 0.7874 0.5842)
					(thickness 0.1524)
				)
				(justify mirror)
			)
		)
		(duplicate_pad_numbers_are_jumpers no)
		(fp_line
			(start -1.143 -0.5588)
			(end 1.143 -0.5588)
			(stroke
				(width 0.1)
				(type default)
			)
			(layer "B.SilkS")
		)
		(fp_line
			(start -1.143 0.5588)
			(end -1.143 -0.5588)
			(stroke
				(width 0.1)
				(type default)
			)
			(layer "B.SilkS")
		)
		(fp_line
			(start 1.143 -0.5588)
			(end 1.143 0.5588)
			(stroke
				(width 0.1)
				(type default)
			)
			(layer "B.SilkS")
		)
		(fp_line
			(start 1.143 0.5588)
			(end -1.143 0.5588)
			(stroke
				(width 0.1)
				(type default)
			)
			(layer "B.SilkS")
		)
		(fp_poly
			(pts
				(xy 1.143 0.5588) (xy -1.143 0.5588) (xy -1.143 -0.5588) (xy 1.143 -0.5588)
			)
			(stroke
				(width 0)
				(type default)
			)
			(fill no)
			(layer "B.CrtYd")
		)
		(fp_line
			(start -0.508 -0.3048)
			(end 0.508 -0.3048)
			(stroke
				(width 0.1)
				(type default)
			)
			(layer "B.Fab")
		)
		(fp_line
			(start -0.508 0.3048)
			(end -0.508 -0.3048)
			(stroke
				(width 0.1)
				(type default)
			)
			(layer "B.Fab")
		)
		(fp_line
			(start 0.508 -0.3048)
			(end 0.508 0.3048)
			(stroke
				(width 0.1)
				(type default)
			)
			(layer "B.Fab")
		)
		(fp_line
			(start 0.508 0.3048)
			(end -0.508 0.3048)
			(stroke
				(width 0.1)
				(type default)
			)
			(layer "B.Fab")
		)
		(pad "1" smd rect
			(at 0.5334 0 180)
			(size 0.7112 0.6096)
			(layers "B.Cu" "B.Mask" "B.Paste")
			(net "XP1R8V_FPGA_VCCAUX")
		)
		(pad "2" smd rect
			(at -0.5334 0 180)
			(size 0.7112 0.6096)
			(layers "B.Cu" "B.Mask" "B.Paste")
			(net "SG")
		)
		(zone
			(layer "B.Cu")
			(hatch none 0.5)
			(connect_pads
				(clearance 0)
			)
			(min_thickness 0.25)
			(keepout
				(tracks not_allowed)
				(vias allowed)
				(pads allowed)
				(copperpour not_allowed)
				(footprints allowed)
			)
			(placement
				(enabled no)
				(sheetname "")
			)
			(fill
				(thermal_gap 0.5)
				(thermal_bridge_width 0.5)
				(island_removal_mode 0)
			)
			(polygon
				(pts
					(xy 110.4138 -43.9166) (xy 110.4138 -44.5262) (xy 110.2614 -44.5262) (xy 110.2614 -43.9166)
				)
			)
		)
		(zone
			(layer "B.Cu")
			(hatch none 0.5)
			(connect_pads
				(clearance 0)
			)
			(min_thickness 0.25)
			(keepout
				(tracks allowed)
				(vias not_allowed)
				(pads allowed)
				(copperpour not_allowed)
				(footprints allowed)
			)
			(placement
				(enabled no)
				(sheetname "")
			)
			(fill
				(thermal_gap 0.5)
				(thermal_bridge_width 0.5)
				(island_removal_mode 0)
			)
			(polygon
				(pts
					(xy 110.4138 -43.9166) (xy 110.4138 -44.5262) (xy 110.2614 -44.5262) (xy 110.2614 -43.9166)
				)
			)
		)
	)
	(footprint ""
		(layer "B.Cu")
		(at 113.847118 -46.322996 -90)
		(property "Reference" "R437"
			(at 1.999996 43.139868 270)
			(unlocked yes)
			(layer "B.SilkS")
			(effects
				(font
					(size 0.635 0.4064)
					(thickness 0.1524)
				)
				(justify mirror)
			)
		)
		(property "Value" "VAL*"
			(at 0 3.718306 270)
			(unlocked yes)
			(layer "B.Fab")
			(hide yes)
			(effects
				(font
					(size 0.7874 0.5842)
					(thickness 0.127)
				)
				(justify mirror)
			)
		)
		(property "Tolerance" "TOL*"
			(at 0 4.861306 270)
			(unlocked yes)
			(layer "Cmts.User")
			(hide yes)
			(effects
				(font
					(size 0.7874 0.5842)
					(thickness 0.127)
				)
				(justify mirror)
			)
		)
		(property "User Part Number" "PARTNUM*"
			(at 0 2.575306 270)
			(unlocked yes)
			(layer "Cmts.User")
			(hide yes)
			(effects
				(font
					(size 0.7874 0.5842)
					(thickness 0.127)
				)
				(justify mirror)
			)
		)
		(property "Device Type" "RESISTOR-G155-11502-01,15KOHM,A"
			(at 0 1.432306 270)
			(unlocked yes)
			(layer "B.Fab")
			(hide yes)
			(effects
				(font
					(size 0.7874 0.5842)
					(thickness 0.127)
				)
				(justify mirror)
			)
		)
		(duplicate_pad_numbers_are_jumpers no)
		(fp_line
			(start -0.970026 0.4699)
			(end 0.970026 0.4699)
			(stroke
				(width 0.1)
				(type default)
			)
			(layer "B.SilkS")
		)
		(fp_line
			(start 0.970026 0.4699)
			(end 0.970026 -0.4699)
			(stroke
				(width 0.1)
				(type default)
			)
			(layer "B.SilkS")
		)
		(fp_line
			(start -0.970026 -0.4699)
			(end -0.970026 0.4699)
			(stroke
				(width 0.1)
				(type default)
			)
			(layer "B.SilkS")
		)
		(fp_line
			(start 0.970026 -0.4699)
			(end -0.970026 -0.4699)
			(stroke
				(width 0.1)
				(type default)
			)
			(layer "B.SilkS")
		)
		(fp_poly
			(pts
				(xy 0.970026 0.4699) (xy -0.970026 0.4699) (xy -0.970026 -0.4699) (xy 0.970026 -0.4699)
			)
			(stroke
				(width 0)
				(type default)
			)
			(fill no)
			(layer "B.CrtYd")
		)
		(fp_line
			(start -0.508 0.3048)
			(end 0.508 0.3048)
			(stroke
				(width 0.1)
				(type default)
			)
			(layer "B.Fab")
		)
		(fp_line
			(start 0.508 0.3048)
			(end 0.508 -0.3048)
			(stroke
				(width 0.1)
				(type default)
			)
			(layer "B.Fab")
		)
		(fp_line
			(start -0.508 -0.3048)
			(end -0.508 0.3048)
			(stroke
				(width 0.1)
				(type default)
			)
			(layer "B.Fab")
		)
		(fp_line
			(start 0.508 -0.3048)
			(end -0.508 -0.3048)
			(stroke
				(width 0.1)
				(type default)
			)
			(layer "B.Fab")
		)
		(pad "1" smd circle
			(at 0.500126 0 90)
			(size 0.635 0.635)
			(layers "B.Cu" "B.Mask" "B.Paste")
			(net "SG")
		)
		(pad "2" smd circle
			(at -0.500126 0 90)
			(size 0.635 0.635)
			(layers "B.Cu" "B.Mask" "B.Paste")
			(net "MAC_USB_DM")
		)
	)
	(footprint ""
		(layer "B.Cu")
		(at 13.462 -66.167 90)
		(property "Reference" "R494"
			(at 0 1.23063 270)
			(unlocked yes)
			(layer "B.SilkS")
			(effects
				(font
					(size 0.7874 0.5842)
					(thickness 0.1524)
				)
				(justify mirror)
			)
		)
		(property "Value" "VAL*"
			(at -0.02032 2.13233 90)
			(unlocked yes)
			(layer "B.Fab")
			(hide yes)
			(effects
				(font
					(size 0.7874 0.5842)
					(thickness 0.1524)
				)
				(justify mirror)
			)
		)
		(property "Tolerance" "TOL*"
			(at -0.044704 3.05435 90)
			(unlocked yes)
			(layer "Cmts.User")
			(hide yes)
			(effects
				(font
					(size 0.7874 0.5842)
					(thickness 0.1524)
				)
				(justify mirror)
			)
		)
		(property "User Part Number" "PARTNUM*"
			(at -0.02032 4.024884 90)
			(unlocked yes)
			(layer "Cmts.User")
			(hide yes)
			(effects
				(font
					(size 0.7874 0.5842)
					(thickness 0.1524)
				)
				(justify mirror)
			)
		)
		(property "Device Type" "RESISTOR-G155-100R0-J0,0OHM,-"
			(at -0.008382 1.210564 90)
			(unlocked yes)
			(layer "B.Fab")
			(hide yes)
			(effects
				(font
					(size 0.7874 0.5842)
					(thickness 0.1524)
				)
				(justify mirror)
			)
		)
		(duplicate_pad_numbers_are_jumpers no)
		(fp_line
			(start 1.143 -0.5588)
			(end 1.143 0.5588)
			(stroke
				(width 0.1)
				(type default)
			)
			(layer "B.SilkS")
		)
		(fp_line
			(start -1.143 -0.5588)
			(end 1.143 -0.5588)
			(stroke
				(width 0.1)
				(type default)
			)
			(layer "B.SilkS")
		)
		(fp_line
			(start 1.143 0.5588)
			(end -1.143 0.5588)
			(stroke
				(width 0.1)
				(type default)
			)
			(layer "B.SilkS")
		)
		(fp_line
			(start -1.143 0.5588)
			(end -1.143 -0.5588)
			(stroke
				(width 0.1)
				(type default)
			)
			(layer "B.SilkS")
		)
		(fp_poly
			(pts
				(xy 1.143 0.5588) (xy -1.143 0.5588) (xy -1.143 -0.5588) (xy 1.143 -0.5588)
			)
			(stroke
				(width 0)
				(type default)
			)
			(fill no)
			(layer "B.CrtYd")
		)
		(fp_line
			(start 0.508 -0.3048)
			(end 0.508 0.3048)
			(stroke
				(width 0.1)
				(type default)
			)
			(layer "B.Fab")
		)
		(fp_line
			(start -0.508 -0.3048)
			(end 0.508 -0.3048)
			(stroke
				(width 0.1)
				(type default)
			)
			(layer "B.Fab")
		)
		(fp_line
			(start 0.508 0.3048)
			(end -0.508 0.3048)
			(stroke
				(width 0.1)
				(type default)
			)
			(layer "B.Fab")
		)
		(fp_line
			(start -0.508 0.3048)
			(end -0.508 -0.3048)
			(stroke
				(width 0.1)
				(type default)
			)
			(layer "B.Fab")
		)
		(pad "1" smd rect
			(at 0.5334 0 270)
			(size 0.7112 0.6096)
			(layers "B.Cu" "B.Mask" "B.Paste")
			(net "UNNAMED_12_CAPACITOR_I328_2")
		)
		(pad "2" smd rect
			(at -0.5334 0 270)
			(size 0.7112 0.6096)
			(layers "B.Cu" "B.Mask" "B.Paste")
			(net "UNNAMED_12_74HCT2G125DPTSSOP8_6")
		)
		(zone
			(layer "B.Cu")
			(hatch none 0.5)
			(connect_pads
				(clearance 0)
			)
			(min_thickness 0.25)
			(keepout
				(tracks allowed)
				(vias not_allowed)
				(pads allowed)
				(copperpour not_allowed)
				(footprints allowed)
			)
			(placement
				(enabled no)
				(sheetname "")
			)
			(fill
				(thermal_gap 0.5)
				(thermal_bridge_width 0.5)
				(island_removal_mode 0)
			)
			(polygon
				(pts
					(xy 13.7668 -66.2432) (xy 13.1572 -66.2432) (xy 13.1572 -66.0908) (xy 13.7668 -66.0908)
				)
			)
		)
		(zone
			(layer "B.Cu")
			(hatch none 0.5)
			(connect_pads
				(clearance 0)
			)
			(min_thickness 0.25)
			(keepout
				(tracks not_allowed)
				(vias allowed)
				(pads allowed)
				(copperpour not_allowed)
				(footprints allowed)
			)
			(placement
				(enabled no)
				(sheetname "")
			)
			(fill
				(thermal_gap 0.5)
				(thermal_bridge_width 0.5)
				(island_removal_mode 0)
			)
			(polygon
				(pts
					(xy 13.7668 -66.2432) (xy 13.1572 -66.2432) (xy 13.1572 -66.0908) (xy 13.7668 -66.0908)
				)
			)
		)
	)
	(footprint ""
		(layer "B.Cu")
		(at 107.84713 -54.323234 -90)
		(property "Reference" "C162"
			(at -0.286766 -1.34112 270)
			(unlocked yes)
			(layer "B.SilkS")
			(effects
				(font
					(size 0.635 0.4064)
					(thickness 0.1524)
				)
				(justify mirror)
			)
		)
		(property "Value" "VAL*"
			(at 0 3.718306 270)
			(unlocked yes)
			(layer "B.Fab")
			(hide yes)
			(effects
				(font
					(size 0.7874 0.5842)
					(thickness 0.127)
				)
				(justify mirror)
			)
		)
		(property "Tolerance" "TOL*"
			(at 0 4.861306 270)
			(unlocked yes)
			(layer "Cmts.User")
			(hide yes)
			(effects
				(font
					(size 0.7874 0.5842)
					(thickness 0.127)
				)
				(justify mirror)
			)
		)
		(property "User Part Number" "PARTNUM*"
			(at 0 2.575306 270)
			(unlocked yes)
			(layer "Cmts.User")
			(hide yes)
			(effects
				(font
					(size 0.7874 0.5842)
					(thickness 0.127)
				)
				(justify mirror)
			)
		)
		(property "Device Type" "CAPACITOR-G105-0B104-CK,0.1UF,A"
			(at 0 1.432306 270)
			(unlocked yes)
			(layer "B.Fab")
			(hide yes)
			(effects
				(font
					(size 0.7874 0.5842)
					(thickness 0.127)
				)
				(justify mirror)
			)
		)
		(duplicate_pad_numbers_are_jumpers no)
		(fp_line
			(start -0.970026 0.4699)
			(end 0.970026 0.4699)
			(stroke
				(width 0.1)
				(type default)
			)
			(layer "B.SilkS")
		)
		(fp_line
			(start 0.970026 0.4699)
			(end 0.970026 -0.4699)
			(stroke
				(width 0.1)
				(type default)
			)
			(layer "B.SilkS")
		)
		(fp_line
			(start -0.970026 -0.4699)
			(end -0.970026 0.4699)
			(stroke
				(width 0.1)
				(type default)
			)
			(layer "B.SilkS")
		)
		(fp_line
			(start 0.970026 -0.4699)
			(end -0.970026 -0.4699)
			(stroke
				(width 0.1)
				(type default)
			)
			(layer "B.SilkS")
		)
		(fp_poly
			(pts
				(xy 0.970026 0.4699) (xy -0.970026 0.4699) (xy -0.970026 -0.4699) (xy 0.970026 -0.4699)
			)
			(stroke
				(width 0)
				(type default)
			)
			(fill no)
			(layer "B.CrtYd")
		)
		(fp_line
			(start -0.508 0.3048)
			(end 0.508 0.3048)
			(stroke
				(width 0.1)
				(type default)
			)
			(layer "B.Fab")
		)
		(fp_line
			(start 0.508 0.3048)
			(end 0.508 -0.3048)
			(stroke
				(width 0.1)
				(type default)
			)
			(layer "B.Fab")
		)
		(fp_line
			(start -0.508 -0.3048)
			(end -0.508 0.3048)
			(stroke
				(width 0.1)
				(type default)
			)
			(layer "B.Fab")
		)
		(fp_line
			(start 0.508 -0.3048)
			(end -0.508 -0.3048)
			(stroke
				(width 0.1)
				(type default)
			)
			(layer "B.Fab")
		)
		(pad "1" smd circle
			(at 0.500126 0 90)
			(size 0.635 0.635)
			(layers "B.Cu" "B.Mask" "B.Paste")
			(net "XP3R3V_FPGA")
		)
		(pad "2" smd circle
			(at -0.500126 0 90)
			(size 0.635 0.635)
			(layers "B.Cu" "B.Mask" "B.Paste")
			(net "SG")
		)
	)
)
